# S9S_MB_2U (Grand Teton) — schematic netlist excerpt (pin names and nets, part order shuffled) for the footprints in the layout excerpt that follows; sources: Cadence DE-HDL packaged netlist, KiCad conversion of 03242023_DA0F0TMBIJ0_F0T_Motherboard_J_brd_V01_OCP.brd

R2391  Q_RES  0 5% CHIP  pkg 0402LF  page 274 : A = SMB_VR_3V3AUX_SDA_R2 ; B = SMB_DIO_PVCCINFAON_CPU0
C412  Q_CAP  22UF 4V 20% X6S  pkg C0402  page 74 : A = PVCCINFAON_CPU0 ; B = GND

(kicad_pcb
	(version 20260206)
	(generator "pcbnew")
	(generator_version "10.0")
	(general
		(thickness 1.6)
		(legacy_teardrops no)
	)
	(paper "A4")
	(title_block
		(title "03242023_DA0F0TMBIJ0_F0T_Motherboard_J_brd_V01_OCP.brd")
		(comment 1 "Grand Teton / footprints 3696-3697 of 6105")
	)
	(layers
		(0 "F.Cu" signal "TOP")
		(4 "In1.Cu" signal "GND")
		(6 "In2.Cu" signal "IN1")
		(8 "In3.Cu" signal "GND1")
		(10 "In4.Cu" signal "IN2")
		(12 "In5.Cu" signal "GND2")
		(14 "In6.Cu" signal "IN3")
		(16 "In7.Cu" signal "GND3")
		(18 "In8.Cu" signal "VCC")
		(20 "In9.Cu" signal "VCC1")
		(22 "In10.Cu" signal "GND4")
		(24 "In11.Cu" signal "IN4")
		(26 "In12.Cu" signal "GND5")
		(28 "In13.Cu" signal "IN5")
		(30 "In14.Cu" signal "GND6")
		(32 "In15.Cu" signal "IN6")
		(34 "In16.Cu" signal "GND7")
		(2 "B.Cu" signal "BOTTOM")
		(9 "F.Adhes" user "F.Adhesive")
		(11 "B.Adhes" user "B.Adhesive")
		(13 "F.Paste" user "Package Geometry/Pastemask Top")
		(15 "B.Paste" user "Package Geometry/Pastemask Bottom")
		(5 "F.SilkS" user "Ref Des/Silkscreen Top")
		(7 "B.SilkS" user "Ref Des/Silkscreen Bottom")
		(1 "F.Mask" user "Board Geometry/Soldermask Top")
		(3 "B.Mask" user "Board Geometry/Soldermask Bottom")
		(17 "Dwgs.User" user "User.Drawings")
		(19 "Cmts.User" user "User.Comments")
		(21 "Eco1.User" user "User.Eco1")
		(23 "Eco2.User" user "User.Eco2")
		(25 "Edge.Cuts" user "Board Geometry/Outline")
		(27 "Margin" user)
		(31 "F.CrtYd" user "Package Geometry/Place Bound Top")
		(29 "B.CrtYd" user "Package Geometry/Place Bound Bottom")
		(35 "F.Fab" user "Ref Des/Assembly Top")
		(33 "B.Fab" user "Ref Des/Assembly Bottom")
	)
	(footprint ""
		(layer "F.Cu")
		(at 366.48263 -238.162338 90)
		(property "Reference" "C412"
			(at 0 0 90)
			(layer "F.SilkS")
			(hide yes)
			(effects
				(font
					(size 1.27 1.27)
				)
			)
		)
		(property "Value" ""
			(at 0 0 90)
			(layer "F.Fab")
			(effects
				(font
					(size 1.27 1.27)
				)
			)
		)
		(duplicate_pad_numbers_are_jumpers no)
		(fp_line
			(start 0.7874 -0.4064)
			(end 0.7874 0.4064)
			(stroke
				(width 0.1524)
				(type default)
			)
			(layer "F.SilkS")
		)
		(fp_line
			(start -0.7874 -0.4064)
			(end 0.7874 -0.4064)
			(stroke
				(width 0.1524)
				(type default)
			)
			(layer "F.SilkS")
		)
		(fp_line
			(start 0.7874 0.4064)
			(end -0.7874 0.4064)
			(stroke
				(width 0.1524)
				(type default)
			)
			(layer "F.SilkS")
		)
		(fp_line
			(start -0.7874 0.4064)
			(end -0.7874 -0.4064)
			(stroke
				(width 0.1524)
				(type default)
			)
			(layer "F.SilkS")
		)
		(fp_line
			(start -0.12065 -0.305054)
			(end -0.12065 -0.2794)
			(stroke
				(width 0.1)
				(type default)
			)
			(layer "F.Fab")
		)
		(fp_line
			(start -0.67945 -0.305054)
			(end -0.12065 -0.305054)
			(stroke
				(width 0.1)
				(type default)
			)
			(layer "F.Fab")
		)
		(fp_line
			(start 0.67945 -0.3048)
			(end 0.67945 0.3048)
			(stroke
				(width 0.1)
				(type default)
			)
			(layer "F.Fab")
		)
		(fp_line
			(start 0.12065 -0.3048)
			(end 0.67945 -0.3048)
			(stroke
				(width 0.1)
				(type default)
			)
			(layer "F.Fab")
		)
		(fp_line
			(start 0.12065 -0.2794)
			(end 0.12065 -0.3048)
			(stroke
				(width 0.1)
				(type default)
			)
			(layer "F.Fab")
		)
		(fp_line
			(start -0.12065 -0.2794)
			(end 0.12065 -0.2794)
			(stroke
				(width 0.1)
				(type default)
			)
			(layer "F.Fab")
		)
		(fp_line
			(start 0.120396 0.2794)
			(end -0.12065 0.2794)
			(stroke
				(width 0.1)
				(type default)
			)
			(layer "F.Fab")
		)
		(fp_line
			(start -0.12065 0.2794)
			(end -0.12065 0.3048)
			(stroke
				(width 0.1)
				(type default)
			)
			(layer "F.Fab")
		)
		(fp_line
			(start 0.67945 0.3048)
			(end 0.120396 0.3048)
			(stroke
				(width 0.1)
				(type default)
			)
			(layer "F.Fab")
		)
		(fp_line
			(start 0.120396 0.3048)
			(end 0.120396 0.2794)
			(stroke
				(width 0.1)
				(type default)
			)
			(layer "F.Fab")
		)
		(fp_line
			(start -0.12065 0.3048)
			(end -0.67945 0.3048)
			(stroke
				(width 0.1)
				(type default)
			)
			(layer "F.Fab")
		)
		(fp_line
			(start -0.67945 0.3048)
			(end -0.67945 -0.305054)
			(stroke
				(width 0.1)
				(type default)
			)
			(layer "F.Fab")
		)
		(pad "1" smd circle
			(at -0.40005 0 90)
			(size 0 0)
			(layers "F.Cu" "F.Mask" "F.Paste")
			(net "PVCCINFAON_CPU0")
		)
		(pad "2" smd circle
			(at 0.40005 0 90)
			(size 0 0)
			(layers "F.Cu" "F.Mask" "F.Paste")
			(net "GND")
		)
	)
	(footprint ""
		(layer "F.Cu")
		(at 430.600104 -130.329178 180)
		(property "Reference" "R2391"
			(at 0 0 180)
			(layer "F.SilkS")
			(hide yes)
			(effects
				(font
					(size 1.27 1.27)
				)
			)
		)
		(property "Value" ""
			(at 0 0 180)
			(layer "F.Fab")
			(effects
				(font
					(size 1.27 1.27)
				)
			)
		)
		(duplicate_pad_numbers_are_jumpers no)
		(fp_line
			(start 0.7874 0.4064)
			(end -0.7874 0.4064)
			(stroke
				(width 0.1524)
				(type default)
			)
			(layer "F.SilkS")
		)
		(fp_line
			(start 0.7874 -0.4064)
			(end 0.7874 0.4064)
			(stroke
				(width 0.1524)
				(type default)
			)
			(layer "F.SilkS")
		)
		(fp_line
			(start -0.7874 0.4064)
			(end -0.7874 -0.4064)
			(stroke
				(width 0.1524)
				(type default)
			)
			(layer "F.SilkS")
		)
		(fp_line
			(start -0.7874 -0.4064)
			(end 0.7874 -0.4064)
			(stroke
				(width 0.1524)
				(type default)
			)
			(layer "F.SilkS")
		)
		(fp_line
			(start 0.67945 0.3048)
			(end 0.120396 0.3048)
			(stroke
				(width 0.1)
				(type default)
			)
			(layer "F.Fab")
		)
		(fp_line
			(start 0.67945 -0.3048)
			(end 0.67945 0.3048)
			(stroke
				(width 0.1)
				(type default)
			)
			(layer "F.Fab")
		)
		(fp_line
			(start 0.12065 -0.2794)
			(end 0.12065 -0.3048)
			(stroke
				(width 0.1)
				(type default)
			)
			(layer "F.Fab")
		)
		(fp_line
			(start 0.12065 -0.3048)
			(end 0.67945 -0.3048)
			(stroke
				(width 0.1)
				(type default)
			)
			(layer "F.Fab")
		)
		(fp_line
			(start 0.120396 0.3048)
			(end 0.120396 0.2794)
			(stroke
				(width 0.1)
				(type default)
			)
			(layer "F.Fab")
		)
		(fp_line
			(start 0.120396 0.2794)
			(end -0.12065 0.2794)
			(stroke
				(width 0.1)
				(type default)
			)
			(layer "F.Fab")
		)
		(fp_line
			(start -0.12065 0.3048)
			(end -0.67945 0.3048)
			(stroke
				(width 0.1)
				(type default)
			)
			(layer "F.Fab")
		)
		(fp_line
			(start -0.12065 0.2794)
			(end -0.12065 0.3048)
			(stroke
				(width 0.1)
				(type default)
			)
			(layer "F.Fab")
		)
		(fp_line
			(start -0.12065 -0.2794)
			(end 0.12065 -0.2794)
			(stroke
				(width 0.1)
				(type default)
			)
			(layer "F.Fab")
		)
		(fp_line
			(start -0.12065 -0.305054)
			(end -0.12065 -0.2794)
			(stroke
				(width 0.1)
				(type default)
			)
			(layer "F.Fab")
		)
		(fp_line
			(start -0.67945 0.3048)
			(end -0.67945 -0.305054)
			(stroke
				(width 0.1)
				(type default)
			)
			(layer "F.Fab")
		)
		(fp_line
			(start -0.67945 -0.305054)
			(end -0.12065 -0.305054)
			(stroke
				(width 0.1)
				(type default)
			)
			(layer "F.Fab")
		)
		(pad "1" smd circle
			(at -0.40005 0 180)
			(size 0 0)
			(layers "F.Cu" "F.Mask" "F.Paste")
			(net "SMB_VR_3V3AUX_SDA_R2")
		)
		(pad "2" smd circle
			(at 0.40005 0 180)
			(size 0 0)
			(layers "F.Cu" "F.Mask" "F.Paste")
			(net "SMB_DIO_PVCCINFAON_CPU0")
		)
	)
)
